(kicad_pcb
	(version 20241229)
	(generator "pcbnew")
	(generator_version "9.0")
	(general
		(thickness 1.61)
		(legacy_teardrops no)
	)
	(paper "A3")
	(title_block
		(title "SO-DIMM DDR5 Tester")
		(date "2025-11-26")
		(rev "1.3.0")
		(comment 9 "footprints 104-108 of 627")
	)
	(layers
		(0 "F.Cu" signal)
		(4 "In1.Cu" power)
		(6 "In2.Cu" mixed)
		(8 "In3.Cu" power)
		(10 "In4.Cu" mixed)
		(12 "In5.Cu" power)
		(14 "In6.Cu" mixed)
		(16 "In7.Cu" power)
		(18 "In8.Cu" power)
		(20 "In9.Cu" mixed)
		(22 "In10.Cu" power)
		(2 "B.Cu" signal)
		(9 "F.Adhes" user "F.Adhesive")
		(11 "B.Adhes" user "B.Adhesive")
		(13 "F.Paste" user)
		(15 "B.Paste" user)
		(5 "F.SilkS" user "F.Silkscreen")
		(7 "B.SilkS" user "B.Silkscreen")
		(1 "F.Mask" user)
		(3 "B.Mask" user)
		(17 "Dwgs.User" user "User.Drawings")
		(19 "Cmts.User" user "User.Comments")
		(21 "Eco1.User" user "User.Eco1")
		(23 "Eco2.User" user "User.Eco2")
		(25 "Edge.Cuts" user)
		(27 "Margin" user)
		(31 "F.CrtYd" user "F.Courtyard")
		(29 "B.CrtYd" user "B.Courtyard")
		(35 "F.Fab" user)
		(33 "B.Fab" user)
	)
	(footprint "antmicro-footprints:R_0402_1005Metric"
		(layer "F.Cu")
		(at 190.545 138.9 90)
		(descr "Resistor SMD 0402")
		(tags "resistor SMD 0402")
		(property "Reference" "R161"
			(at -1.122484 -0.772697 90)
			(layer "F.SilkS")
			(hide yes)
			(effects
				(font
					(size 0.7 0.7)
					(thickness 0.15)
				)
				(justify left bottom)
			)
		)
		(property "Value" "R_47k_0402"
			(at -1.011843 1.772047 90)
			(layer "F.Fab")
			(effects
				(font
					(size 0.7 0.7)
					(thickness 0.15)
				)
				(justify left bottom)
			)
		)
		(property "Datasheet" "https://www.bourns.com/docs/product-datasheets/cr.pdf"
			(at 0 0 90)
			(layer "F.Fab")
			(hide yes)
			(effects
				(font
					(size 1.27 1.27)
					(thickness 0.15)
				)
			)
		)
		(property "Author" "Antmicro"
			(at 329.445 -51.645 0)
			(layer "F.Fab")
			(hide yes)
			(effects
				(font
					(size 1 1)
					(thickness 0.15)
				)
			)
		)
		(property "License" "Apache-2.0"
			(at 329.445 -51.645 0)
			(layer "F.Fab")
			(hide yes)
			(effects
				(font
					(size 1 1)
					(thickness 0.15)
				)
			)
		)
		(property "MPN" "CR0402-FX-4702GLF"
			(at 329.445 -51.645 0)
			(layer "F.Fab")
			(hide yes)
			(effects
				(font
					(size 1 1)
					(thickness 0.15)
				)
			)
		)
		(property "Manufacturer" "Bourns"
			(at 329.445 -51.645 0)
			(layer "F.Fab")
			(hide yes)
			(effects
				(font
					(size 1 1)
					(thickness 0.15)
				)
			)
		)
		(property "Tolerance" "1%"
			(at 329.445 -51.645 0)
			(layer "F.Fab")
			(hide yes)
			(effects
				(font
					(size 1 1)
					(thickness 0.15)
				)
			)
		)
		(property "Val" "47k"
			(at 329.445 -51.645 0)
			(layer "F.Fab")
			(hide yes)
			(effects
				(font
					(size 1 1)
					(thickness 0.15)
				)
			)
		)
		(sheetname "/Supply/")
		(sheetfile "supply.kicad_sch")
		(attr smd)
		(fp_rect
			(start -0.93 -0.47)
			(end 0.93 0.47)
			(stroke
				(width 0.05)
				(type solid)
			)
			(fill no)
			(layer "F.CrtYd")
		)
		(fp_rect
			(start -0.5 -0.25)
			(end 0.5 0.25)
			(stroke
				(width 0.15)
				(type solid)
			)
			(fill no)
			(layer "F.Fab")
		)
		(pad "1" smd roundrect
			(at -0.485 0 90)
			(size 0.59 0.64)
			(layers "F.Cu" "F.Mask" "F.Paste")
			(roundrect_rratio 0.25)
			(net 1 "GND")
			(pintype "passive")
		)
		(pad "2" smd roundrect
			(at 0.485 0 90)
			(size 0.59 0.64)
			(layers "F.Cu" "F.Mask" "F.Paste")
			(roundrect_rratio 0.25)
			(net 242 "FPGA_POWER_OFF")
			(pintype "passive")
		)
	)
	(footprint "antmicro-footprints:NetTie-2_SMD_Pad0.127mm"
		(layer "F.Cu")
		(at 187.85 179.5 180)
		(descr "Net tie, 2 pin, 0.127mm  SMD pads")
		(tags "net tie")
		(property "Reference" "NT10"
			(at -0.128 -1.345 180)
			(layer "F.SilkS")
			(hide yes)
			(effects
				(font
					(size 0.7 0.7)
					(thickness 0.15)
				)
				(justify left bottom)
			)
		)
		(property "Value" "Net-Tie_P0.127mm"
			(at 0 1.199 180)
			(layer "F.Fab")
			(effects
				(font
					(size 0.7 0.7)
					(thickness 0.15)
				)
				(justify left bottom)
			)
		)
		(property "Author" "Antmicro"
			(at 375.7 359 0)
			(layer "F.Fab")
			(hide yes)
			(effects
				(font
					(size 1 1)
					(thickness 0.15)
				)
			)
		)
		(property "License" "Apache-2.0"
			(at 375.7 359 0)
			(layer "F.Fab")
			(hide yes)
			(effects
				(font
					(size 1 1)
					(thickness 0.15)
				)
			)
		)
		(property "MPN" ""
			(at 375.7 359 0)
			(layer "F.Fab")
			(hide yes)
			(effects
				(font
					(size 1 1)
					(thickness 0.15)
				)
			)
		)
		(property "Manufacturer" ""
			(at 375.7 359 0)
			(layer "F.Fab")
			(hide yes)
			(effects
				(font
					(size 1 1)
					(thickness 0.15)
				)
			)
		)
		(property ki_fp_filters "Net*Tie*")
		(sheetname "/Supply/")
		(sheetfile "supply.kicad_sch")
		(attr smd exclude_from_pos_files exclude_from_bom)
		(net_tie_pad_groups "1, 2")
		(fp_poly
			(pts
				(xy -0.0635 -0.0635) (xy 0.0625 -0.0635) (xy 0.0625 0.0635) (xy -0.0635 0.0635)
			)
			(stroke
				(width 0)
				(type solid)
			)
			(fill yes)
			(layer "F.Cu")
		)
		(pad "1" smd roundrect
			(at -0.127 0)
			(size 0.127 0.127)
			(layers "F.Cu")
			(roundrect_rratio 0.5)
			(chamfer_ratio 0)
			(chamfer top_left bottom_left)
			(net 246 "/Supply/1V8_SEN_-")
			(pinfunction "1")
			(pintype "passive")
		)
		(pad "2" smd roundrect
			(at 0.126 0 180)
			(size 0.127 0.127)
			(layers "F.Cu")
			(roundrect_rratio 0.5)
			(chamfer_ratio 0)
			(chamfer top_left bottom_left)
			(net 188 "+1V8")
			(pinfunction "2")
			(pintype "passive")
		)
	)
	(footprint "antmicro-footprints:USON-10_2.5x1mm_P0.5mm"
		(layer "F.Cu")
		(at 82.4 191 180)
		(descr "USON-10 2.5x1mm_ Pitch 0.5mm")
		(tags "USON-10 2.5x1mm Pitch 0.5mm")
		(property "Reference" "U11"
			(at 0.018 -1.7 180)
			(layer "F.SilkS")
			(hide yes)
			(effects
				(font
					(size 0.7 0.7)
					(thickness 0.15)
				)
				(justify left bottom)
			)
		)
		(property "Value" "TPD4E05U06QDQARQ1"
			(at 0.018 2.499 180)
			(layer "F.Fab")
			(effects
				(font
					(size 0.7 0.7)
					(thickness 0.15)
				)
				(justify left bottom)
			)
		)
		(property "Datasheet" "https://www.ti.com/lit/ds/symlink/tpd4e05u06-q1.pdf?HQS=dis-mous-null-mousermode-dsf-pf-null-wwe&ts=1663591265741&ref_url=https%253A%252F%252Fwww.mouser.com%252F"
			(at 0 0 180)
			(layer "F.Fab")
			(hide yes)
			(effects
				(font
					(size 1.27 1.27)
					(thickness 0.15)
				)
			)
		)
		(property "Author" "Antmicro"
			(at 164.8 382 0)
			(layer "F.Fab")
			(hide yes)
			(effects
				(font
					(size 1 1)
					(thickness 0.15)
				)
			)
		)
		(property "License" "Apache-2.0"
			(at 164.8 382 0)
			(layer "F.Fab")
			(hide yes)
			(effects
				(font
					(size 1 1)
					(thickness 0.15)
				)
			)
		)
		(property "MPN" "TPD4E05U06QDQARQ1"
			(at 164.8 382 0)
			(layer "F.Fab")
			(hide yes)
			(effects
				(font
					(size 1 1)
					(thickness 0.15)
				)
			)
		)
		(property "Manufacturer" "Texas Instruments"
			(at 164.8 382 0)
			(layer "F.Fab")
			(hide yes)
			(effects
				(font
					(size 1 1)
					(thickness 0.15)
				)
			)
		)
		(sheetname "/HDMI + SD Card/")
		(sheetfile "hdmi-sd-card.kicad_sch")
		(attr smd)
		(fp_line
			(start 0.498 1.398)
			(end -0.5 1.398)
			(stroke
				(width 0.15)
				(type solid)
			)
			(layer "F.SilkS")
		)
		(fp_line
			(start 0.498 -1.401)
			(end -0.5 -1.401)
			(stroke
				(width 0.15)
				(type solid)
			)
			(layer "F.SilkS")
		)
		(fp_circle
			(center -0.68 -1.27)
			(end -0.63 -1.27)
			(stroke
				(width 0.15)
				(type solid)
			)
			(fill yes)
			(layer "F.SilkS")
		)
		(fp_rect
			(start -0.8 -1.5)
			(end 0.8 1.499)
			(stroke
				(width 0.05)
				(type solid)
			)
			(fill no)
			(layer "F.CrtYd")
		)
		(fp_line
			(start 0.498 -1.25)
			(end 0.498 1.249)
			(stroke
				(width 0.15)
				(type solid)
			)
			(layer "F.Fab")
		)
		(fp_line
			(start 0.498 -1.25)
			(end -0.25 -1.25)
			(stroke
				(width 0.15)
				(type solid)
			)
			(layer "F.Fab")
		)
		(fp_line
			(start -0.25 -1.25)
			(end -0.5 -1)
			(stroke
				(width 0.15)
				(type solid)
			)
			(layer "F.Fab")
		)
		(fp_line
			(start -0.5 1.249)
			(end 0.498 1.249)
			(stroke
				(width 0.15)
				(type solid)
			)
			(layer "F.Fab")
		)
		(fp_line
			(start -0.5 -1)
			(end -0.5 1.249)
			(stroke
				(width 0.15)
				(type solid)
			)
			(layer "F.Fab")
		)
		(pad "1" smd roundrect
			(at -0.387 -1 90)
			(size 0.25 0.55)
			(layers "F.Cu" "F.Mask" "F.Paste")
			(roundrect_rratio 0.25)
			(net 296 "/HDMI + SD Card/HDMI_CONN_D0_P")
			(pintype "passive")
		)
		(pad "2" smd roundrect
			(at -0.387 -0.5 90)
			(size 0.25 0.55)
			(layers "F.Cu" "F.Mask" "F.Paste")
			(roundrect_rratio 0.25)
			(net 311 "/HDMI + SD Card/HDMI_CONN_D0_N")
			(pintype "passive")
		)
		(pad "3" smd roundrect
			(at -0.387 0 90)
			(size 0.4 0.55)
			(layers "F.Cu" "F.Mask" "F.Paste")
			(roundrect_rratio 0.25)
			(net 1 "GND")
			(pintype "power_in")
		)
		(pad "4" smd roundrect
			(at -0.387 0.498 90)
			(size 0.25 0.55)
			(layers "F.Cu" "F.Mask" "F.Paste")
			(roundrect_rratio 0.25)
			(net 348 "/HDMI + SD Card/HDMI_CONN_CLK_P")
			(pintype "passive")
		)
		(pad "5" smd roundrect
			(at -0.387 0.998 90)
			(size 0.25 0.55)
			(layers "F.Cu" "F.Mask" "F.Paste")
			(roundrect_rratio 0.25)
			(net 349 "/HDMI + SD Card/HDMI_CONN_CLK_N")
			(pintype "passive")
		)
		(pad "6" smd roundrect
			(at 0.385 0.998 90)
			(size 0.25 0.55)
			(layers "F.Cu" "F.Mask" "F.Paste")
			(roundrect_rratio 0.25)
			(net 349 "/HDMI + SD Card/HDMI_CONN_CLK_N")
			(pintype "passive")
		)
		(pad "7" smd roundrect
			(at 0.385 0.498 90)
			(size 0.25 0.55)
			(layers "F.Cu" "F.Mask" "F.Paste")
			(roundrect_rratio 0.25)
			(net 348 "/HDMI + SD Card/HDMI_CONN_CLK_P")
			(pintype "passive")
		)
		(pad "8" smd roundrect
			(at 0.385 0 90)
			(size 0.4 0.55)
			(layers "F.Cu" "F.Mask" "F.Paste")
			(roundrect_rratio 0.25)
			(net 1 "GND")
			(pintype "passive")
		)
		(pad "9" smd roundrect
			(at 0.385 -0.5 90)
			(size 0.25 0.55)
			(layers "F.Cu" "F.Mask" "F.Paste")
			(roundrect_rratio 0.25)
			(net 311 "/HDMI + SD Card/HDMI_CONN_D0_N")
			(pintype "passive")
		)
		(pad "10" smd roundrect
			(at 0.385 -1 90)
			(size 0.25 0.55)
			(layers "F.Cu" "F.Mask" "F.Paste")
			(roundrect_rratio 0.25)
			(net 296 "/HDMI + SD Card/HDMI_CONN_D0_P")
			(pintype "passive")
		)
	)
	(footprint "antmicro-footprints:TSSOP-8_3x3mm_P0.65mm"
		(layer "F.Cu")
		(at 99.300501 141.576 -90)
		(property "Reference" "U16"
			(at 0.424 -2.699499 270)
			(layer "F.SilkS")
			(effects
				(font
					(size 0.7 0.7)
					(thickness 0.15)
				)
				(justify left bottom)
			)
		)
		(property "Value" "PCA9517ADP"
			(at 0 2.8 270)
			(layer "F.Fab")
			(effects
				(font
					(size 0.7 0.7)
					(thickness 0.15)
				)
				(justify left bottom)
			)
		)
		(property "Datasheet" "https://www.nxp.com/docs/en/data-sheet/PCA9517A.pdf"
			(at 0 0 270)
			(layer "F.Fab")
			(hide yes)
			(effects
				(font
					(size 1.27 1.27)
					(thickness 0.15)
				)
			)
		)
		(property "Author" "Antmicro"
			(at -42.275499 240.876501 0)
			(layer "F.Fab")
			(hide yes)
			(effects
				(font
					(size 1 1)
					(thickness 0.15)
				)
			)
		)
		(property "License" "Apache-2.0"
			(at -42.275499 240.876501 0)
			(layer "F.Fab")
			(hide yes)
			(effects
				(font
					(size 1 1)
					(thickness 0.15)
				)
			)
		)
		(property "MPN" "PCA9517ADP,118"
			(at -42.275499 240.876501 0)
			(layer "F.Fab")
			(hide yes)
			(effects
				(font
					(size 1 1)
					(thickness 0.15)
				)
			)
		)
		(property "Manufacturer" "NXP"
			(at -42.275499 240.876501 0)
			(layer "F.Fab")
			(hide yes)
			(effects
				(font
					(size 1 1)
					(thickness 0.15)
				)
			)
		)
		(sheetname "/I^{2}C/")
		(sheetfile "i2c.kicad_sch")
		(attr smd)
		(fp_line
			(start -1.55 1.561)
			(end 1.552 1.561)
			(stroke
				(width 0.15)
				(type solid)
			)
			(layer "F.SilkS")
		)
		(fp_line
			(start -1.525 -1.537)
			(end 1.552 -1.539)
			(stroke
				(width 0.15)
				(type solid)
			)
			(layer "F.SilkS")
		)
		(fp_circle
			(center -1.87 -1.4)
			(end -1.82 -1.4)
			(stroke
				(width 0.15)
				(type solid)
			)
			(fill yes)
			(layer "F.SilkS")
		)
		(fp_rect
			(start -3.15 -1.789)
			(end 3.15 1.811)
			(stroke
				(width 0.05)
				(type solid)
			)
			(fill no)
			(layer "F.CrtYd")
		)
		(fp_line
			(start -1.55 1.561)
			(end 1.552 1.561)
			(stroke
				(width 0.15)
				(type solid)
			)
			(layer "F.Fab")
		)
		(fp_line
			(start -1.55 -0.937)
			(end -1.55 1.561)
			(stroke
				(width 0.15)
				(type solid)
			)
			(layer "F.Fab")
		)
		(fp_line
			(start -1.55 -0.937)
			(end -0.949 -1.539)
			(stroke
				(width 0.15)
				(type solid)
			)
			(layer "F.Fab")
		)
		(fp_line
			(start -0.949 -1.539)
			(end 1.552 -1.539)
			(stroke
				(width 0.15)
				(type solid)
			)
			(layer "F.Fab")
		)
		(fp_line
			(start 1.552 -1.539)
			(end 1.552 1.561)
			(stroke
				(width 0.15)
				(type solid)
			)
			(layer "F.Fab")
		)
		(pad "1" smd roundrect
			(at -2.148 -0.962 270)
			(size 1.47 0.4)
			(layers "F.Cu" "F.Mask" "F.Paste")
			(roundrect_rratio 0.25)
			(net 267 "VDDSPD")
			(pinfunction "V_{CC(A)}")
			(pintype "power_in")
		)
		(pad "2" smd roundrect
			(at -2.148 -0.313 270)
			(size 1.47 0.4)
			(layers "F.Cu" "F.Mask" "F.Paste")
			(roundrect_rratio 0.25)
			(net 50 "/DDR5 SODIMM/DDR.SCL")
			(pinfunction "SCLA")
			(pintype "input")
		)
		(pad "3" smd roundrect
			(at -2.148 0.338 270)
			(size 1.47 0.4)
			(layers "F.Cu" "F.Mask" "F.Paste")
			(roundrect_rratio 0.25)
			(net 54 "/DDR5 SODIMM/DDR.SDA")
			(pinfunction "SDAA")
			(pintype "bidirectional")
		)
		(pad "4" smd roundrect
			(at -2.148 0.987 270)
			(size 1.47 0.4)
			(layers "F.Cu" "F.Mask" "F.Paste")
			(roundrect_rratio 0.25)
			(net 1 "GND")
			(pinfunction "GND")
			(pintype "power_in")
		)
		(pad "5" smd roundrect
			(at 2.151 0.987 270)
			(size 1.47 0.4)
			(layers "F.Cu" "F.Mask" "F.Paste")
			(roundrect_rratio 0.25)
			(net 387 "Net-(U16-EN)")
			(pinfunction "EN")
			(pintype "input")
		)
		(pad "6" smd roundrect
			(at 2.151 0.338 270)
			(size 1.47 0.4)
			(layers "F.Cu" "F.Mask" "F.Paste")
			(roundrect_rratio 0.25)
			(net 683 "/FPGA bank 14/FPGA_DDR.SDA")
			(pinfunction "SDAB")
			(pintype "bidirectional")
		)
		(pad "7" smd roundrect
			(at 2.151 -0.313 270)
			(size 1.47 0.4)
			(layers "F.Cu" "F.Mask" "F.Paste")
			(roundrect_rratio 0.25)
			(net 682 "/FPGA bank 14/FPGA_DDR.SCL")
			(pinfunction "SCLB")
			(pintype "input")
		)
		(pad "8" smd roundrect
			(at 2.151 -0.962 270)
			(size 1.47 0.4)
			(layers "F.Cu" "F.Mask" "F.Paste")
			(roundrect_rratio 0.25)
			(net 200 "+3V3")
			(pinfunction "V_{CC(B)}")
			(pintype "power_in")
		)
	)
	(footprint "antmicro-footprints:R_0402_1005Metric"
		(layer "F.Cu")
		(at 92.7 194.815 90)
		(descr "Resistor SMD 0402")
		(tags "resistor SMD 0402")
		(property "Reference" "R64"
			(at -1.122484 -0.772697 90)
			(layer "F.SilkS")
			(hide yes)
			(effects
				(font
					(size 0.7 0.7)
					(thickness 0.15)
				)
				(justify left bottom)
			)
		)
		(property "Value" "R_330R_0402"
			(at -1.011843 1.772047 90)
			(layer "F.Fab")
			(effects
				(font
					(size 0.7 0.7)
					(thickness 0.15)
				)
				(justify left bottom)
			)
		)
		(property "Datasheet" "https://www.bourns.com/docs/product-datasheets/cr.pdf"
			(at 0 0 90)
			(layer "F.Fab")
			(hide yes)
			(effects
				(font
					(size 1.27 1.27)
					(thickness 0.15)
				)
			)
		)
		(property "Author" "Antmicro"
			(at 287.515 102.115 0)
			(layer "F.Fab")
			(hide yes)
			(effects
				(font
					(size 1 1)
					(thickness 0.15)
				)
			)
		)
		(property "License" "Apache-2.0"
			(at 287.515 102.115 0)
			(layer "F.Fab")
			(hide yes)
			(effects
				(font
					(size 1 1)
					(thickness 0.15)
				)
			)
		)
		(property "MPN" "CR0402-FX-3300GLF"
			(at 287.515 102.115 0)
			(layer "F.Fab")
			(hide yes)
			(effects
				(font
					(size 1 1)
					(thickness 0.15)
				)
			)
		)
		(property "Manufacturer" "Bourns"
			(at 287.515 102.115 0)
			(layer "F.Fab")
			(hide yes)
			(effects
				(font
					(size 1 1)
					(thickness 0.15)
				)
			)
		)
		(property "Tolerance" "1%"
			(at 287.515 102.115 0)
			(layer "F.Fab")
			(hide yes)
			(effects
				(font
					(size 1 1)
					(thickness 0.15)
				)
			)
		)
		(property "Val" "330R"
			(at 287.515 102.115 0)
			(layer "F.Fab")
			(hide yes)
			(effects
				(font
					(size 1 1)
					(thickness 0.15)
				)
			)
		)
		(sheetname "/Debug FTDI/")
		(sheetfile "debug-ftdi.kicad_sch")
		(attr smd)
		(fp_rect
			(start -0.93 -0.47)
			(end 0.93 0.47)
			(stroke
				(width 0.05)
				(type solid)
			)
			(fill no)
			(layer "F.CrtYd")
		)
		(fp_rect
			(start -0.5 -0.25)
			(end 0.5 0.25)
			(stroke
				(width 0.15)
				(type solid)
			)
			(fill no)
			(layer "F.Fab")
		)
		(pad "1" smd roundrect
			(at -0.485 0 90)
			(size 0.59 0.64)
			(layers "F.Cu" "F.Mask" "F.Paste")
			(roundrect_rratio 0.25)
			(net 315 "Net-(D10-Pad1)")
			(pintype "passive")
		)
		(pad "2" smd roundrect
			(at 0.485 0 90)
			(size 0.59 0.64)
			(layers "F.Cu" "F.Mask" "F.Paste")
			(roundrect_rratio 0.25)
			(net 656 "/Debug FTDI/LED_TX0")
			(pintype "passive")
		)
	)
)
